(kicad_pcb
	(version 20241229)
	(generator "pcbnew")
	(generator_version "9.0")
	(general
		(thickness 1.599998)
		(legacy_teardrops no)
	)
	(paper "A4")
	(title_block
		(date "2023-02-12")
		(rev "1.1.5")
		(comment 9 "footprints 81-88 of 473")
	)
	(layers
		(0 "F.Cu" signal)
		(4 "In1.Cu" power "In1.GND")
		(6 "In2.Cu" signal)
		(8 "In3.Cu" power "In3.GND")
		(10 "In4.Cu" power "In4.VCC")
		(12 "In5.Cu" signal)
		(14 "In6.Cu" power "In6.VCC")
		(2 "B.Cu" signal)
		(9 "F.Adhes" user "F.Adhesive")
		(11 "B.Adhes" user "B.Adhesive")
		(13 "F.Paste" user)
		(15 "B.Paste" user)
		(5 "F.SilkS" user "F.Silkscreen")
		(7 "B.SilkS" user "B.Silkscreen")
		(1 "F.Mask" user)
		(3 "B.Mask" user)
		(17 "Dwgs.User" user "User.Drawings")
		(19 "Cmts.User" user "User.Comments")
		(21 "Eco1.User" user "User.Eco1")
		(23 "Eco2.User" user "User.Eco2")
		(25 "Edge.Cuts" user)
		(27 "Margin" user)
		(31 "F.CrtYd" user "F.Courtyard")
		(29 "B.CrtYd" user "B.Courtyard")
		(35 "F.Fab" user)
		(33 "B.Fab" user)
	)
	(footprint "antmicro-footprints:R_0402_1005Metric"
		(layer "F.Cu")
		(at 177.693 124.113 -90)
		(descr "Resistor SMD 0402")
		(tags "resistor SMD 0402")
		(property "Reference" "R31"
			(at -0.713 -0.407 270)
			(layer "F.SilkS")
			(effects
				(font
					(size 0.7 0.7)
					(thickness 0.15)
				)
				(justify left bottom)
			)
		)
		(property "Value" "R_20k_0402"
			(at 0 1.4 270)
			(layer "F.Fab")
			(effects
				(font
					(size 0.7 0.7)
					(thickness 0.15)
				)
				(justify left bottom)
			)
		)
		(property "Description" "20k resistor in 0402 package with 1% tolerance"
			(at 0 0 270)
			(layer "F.Fab")
			(hide yes)
			(effects
				(font
					(size 1.27 1.27)
					(thickness 0.15)
				)
			)
		)
		(property "Author" "Antmicro"
			(at 53.58 301.806 0)
			(layer "F.Fab")
			(hide yes)
			(effects
				(font
					(size 1 1)
					(thickness 0.15)
				)
			)
		)
		(property "License" "Apache-2.0"
			(at 53.58 301.806 0)
			(layer "F.Fab")
			(hide yes)
			(effects
				(font
					(size 1 1)
					(thickness 0.15)
				)
			)
		)
		(property "MPN" "CR0402-FX-2002GLF"
			(at 53.58 301.806 0)
			(layer "F.Fab")
			(hide yes)
			(effects
				(font
					(size 1 1)
					(thickness 0.15)
				)
			)
		)
		(property "Manufacturer" "Bourns"
			(at 53.58 301.806 0)
			(layer "F.Fab")
			(hide yes)
			(effects
				(font
					(size 1 1)
					(thickness 0.15)
				)
			)
		)
		(property "Tolerance" "1%"
			(at 53.58 301.806 0)
			(layer "F.Fab")
			(hide yes)
			(effects
				(font
					(size 1 1)
					(thickness 0.15)
				)
			)
		)
		(property "Val" "20k"
			(at 53.58 301.806 0)
			(layer "F.Fab")
			(hide yes)
			(effects
				(font
					(size 1 1)
					(thickness 0.15)
				)
			)
		)
		(sheetname "Interfaces")
		(sheetfile "interfaces.kicad_sch")
		(attr smd)
		(fp_rect
			(start -0.93 -0.47)
			(end 0.93 0.47)
			(stroke
				(width 0.05)
				(type solid)
			)
			(fill no)
			(layer "F.CrtYd")
		)
		(fp_rect
			(start -0.5 -0.25)
			(end 0.5 0.25)
			(stroke
				(width 0.15)
				(type solid)
			)
			(fill no)
			(layer "F.Fab")
		)
		(pad "1" smd roundrect
			(at -0.485 0 270)
			(size 0.59 0.64)
			(layers "F.Cu" "F.Mask" "F.Paste")
			(roundrect_rratio 0.25)
			(net 459 "3V3_SYS")
			(pintype "passive")
		)
		(pad "2" smd roundrect
			(at 0.485 0 270)
			(size 0.59 0.64)
			(layers "F.Cu" "F.Mask" "F.Paste")
			(roundrect_rratio 0.25)
			(net 198 "SD_CD")
			(pintype "passive")
		)
	)
	(footprint "antmicro-footprints:R_0402_1005Metric"
		(layer "F.Cu")
		(at 178.201 130.082 -90)
		(descr "Resistor SMD 0402")
		(tags "resistor SMD 0402")
		(property "Reference" "R33"
			(at -0.782 -0.431 270)
			(layer "F.SilkS")
			(effects
				(font
					(size 0.7 0.7)
					(thickness 0.15)
				)
				(justify left bottom)
			)
		)
		(property "Value" "R_20k_0402"
			(at 0 1.4 270)
			(layer "F.Fab")
			(effects
				(font
					(size 0.7 0.7)
					(thickness 0.15)
				)
				(justify left bottom)
			)
		)
		(property "Description" "20k resistor in 0402 package with 1% tolerance"
			(at 0 0 270)
			(layer "F.Fab")
			(hide yes)
			(effects
				(font
					(size 1.27 1.27)
					(thickness 0.15)
				)
			)
		)
		(property "Author" "Antmicro"
			(at 48.119 308.283 0)
			(layer "F.Fab")
			(hide yes)
			(effects
				(font
					(size 1 1)
					(thickness 0.15)
				)
			)
		)
		(property "License" "Apache-2.0"
			(at 48.119 308.283 0)
			(layer "F.Fab")
			(hide yes)
			(effects
				(font
					(size 1 1)
					(thickness 0.15)
				)
			)
		)
		(property "MPN" "CR0402-FX-2002GLF"
			(at 48.119 308.283 0)
			(layer "F.Fab")
			(hide yes)
			(effects
				(font
					(size 1 1)
					(thickness 0.15)
				)
			)
		)
		(property "Manufacturer" "Bourns"
			(at 48.119 308.283 0)
			(layer "F.Fab")
			(hide yes)
			(effects
				(font
					(size 1 1)
					(thickness 0.15)
				)
			)
		)
		(property "Tolerance" "1%"
			(at 48.119 308.283 0)
			(layer "F.Fab")
			(hide yes)
			(effects
				(font
					(size 1 1)
					(thickness 0.15)
				)
			)
		)
		(property "Val" "20k"
			(at 48.119 308.283 0)
			(layer "F.Fab")
			(hide yes)
			(effects
				(font
					(size 1 1)
					(thickness 0.15)
				)
			)
		)
		(sheetname "Interfaces")
		(sheetfile "interfaces.kicad_sch")
		(attr smd)
		(fp_rect
			(start -0.93 -0.47)
			(end 0.93 0.47)
			(stroke
				(width 0.05)
				(type solid)
			)
			(fill no)
			(layer "F.CrtYd")
		)
		(fp_rect
			(start -0.5 -0.25)
			(end 0.5 0.25)
			(stroke
				(width 0.15)
				(type solid)
			)
			(fill no)
			(layer "F.Fab")
		)
		(pad "1" smd roundrect
			(at -0.485 0 270)
			(size 0.59 0.64)
			(layers "F.Cu" "F.Mask" "F.Paste")
			(roundrect_rratio 0.25)
			(net 459 "3V3_SYS")
			(pintype "passive")
		)
		(pad "2" smd roundrect
			(at 0.485 0 270)
			(size 0.59 0.64)
			(layers "F.Cu" "F.Mask" "F.Paste")
			(roundrect_rratio 0.25)
			(net 193 "SD_DAT0")
			(pintype "passive")
		)
	)
	(footprint "antmicro-footprints:R_0402_1005Metric"
		(layer "F.Cu")
		(at 178.836 124.113 90)
		(descr "Resistor SMD 0402")
		(tags "resistor SMD 0402")
		(property "Reference" "R36"
			(at 0.713 0.364 90)
			(layer "F.SilkS")
			(effects
				(font
					(size 0.7 0.7)
					(thickness 0.15)
				)
				(justify left bottom)
			)
		)
		(property "Value" "R_220R_0402"
			(at 0 1.4 90)
			(layer "F.Fab")
			(effects
				(font
					(size 0.7 0.7)
					(thickness 0.15)
				)
				(justify left bottom)
			)
		)
		(property "Description" "220R resistor in 0402 package with 1% tolerance"
			(at 0 0 90)
			(layer "F.Fab")
			(hide yes)
			(effects
				(font
					(size 1.27 1.27)
					(thickness 0.15)
				)
			)
		)
		(property "Author" "Antmicro"
			(at 302.949 -54.723 0)
			(layer "F.Fab")
			(hide yes)
			(effects
				(font
					(size 1 1)
					(thickness 0.15)
				)
			)
		)
		(property "License" "Apache-2.0"
			(at 302.949 -54.723 0)
			(layer "F.Fab")
			(hide yes)
			(effects
				(font
					(size 1 1)
					(thickness 0.15)
				)
			)
		)
		(property "MPN" "CR0402-FX-2200GLF"
			(at 302.949 -54.723 0)
			(layer "F.Fab")
			(hide yes)
			(effects
				(font
					(size 1 1)
					(thickness 0.15)
				)
			)
		)
		(property "Manufacturer" "Bourns"
			(at 302.949 -54.723 0)
			(layer "F.Fab")
			(hide yes)
			(effects
				(font
					(size 1 1)
					(thickness 0.15)
				)
			)
		)
		(property "Tolerance" "1%"
			(at 302.949 -54.723 0)
			(layer "F.Fab")
			(hide yes)
			(effects
				(font
					(size 1 1)
					(thickness 0.15)
				)
			)
		)
		(property "Val" "220R"
			(at 302.949 -54.723 0)
			(layer "F.Fab")
			(hide yes)
			(effects
				(font
					(size 1 1)
					(thickness 0.15)
				)
			)
		)
		(sheetname "Interfaces")
		(sheetfile "interfaces.kicad_sch")
		(attr smd)
		(fp_rect
			(start -0.93 -0.47)
			(end 0.93 0.47)
			(stroke
				(width 0.05)
				(type solid)
			)
			(fill no)
			(layer "F.CrtYd")
		)
		(fp_rect
			(start -0.5 -0.25)
			(end 0.5 0.25)
			(stroke
				(width 0.15)
				(type solid)
			)
			(fill no)
			(layer "F.Fab")
		)
		(pad "1" smd roundrect
			(at -0.485 0 90)
			(size 0.59 0.64)
			(layers "F.Cu" "F.Mask" "F.Paste")
			(roundrect_rratio 0.25)
			(net 198 "SD_CD")
			(pintype "passive")
		)
		(pad "2" smd roundrect
			(at 0.485 0 90)
			(size 0.59 0.64)
			(layers "F.Cu" "F.Mask" "F.Paste")
			(roundrect_rratio 0.25)
			(net 85 "Net-(J3-CD1)")
			(pintype "passive")
		)
	)
	(footprint "antmicro-footprints:R_0402_1005Metric"
		(layer "F.Cu")
		(at 172.74 130.082 -90)
		(descr "Resistor SMD 0402")
		(tags "resistor SMD 0402")
		(property "Reference" "R37"
			(at -0.782 -0.403 270)
			(layer "F.SilkS")
			(effects
				(font
					(size 0.7 0.7)
					(thickness 0.15)
				)
				(justify left bottom)
			)
		)
		(property "Value" "R_20k_0402"
			(at 0 1.4 270)
			(layer "F.Fab")
			(effects
				(font
					(size 0.7 0.7)
					(thickness 0.15)
				)
				(justify left bottom)
			)
		)
		(property "Description" "20k resistor in 0402 package with 1% tolerance"
			(at 0 0 270)
			(layer "F.Fab")
			(hide yes)
			(effects
				(font
					(size 1.27 1.27)
					(thickness 0.15)
				)
			)
		)
		(property "Author" "Antmicro"
			(at 42.658 302.822 0)
			(layer "F.Fab")
			(hide yes)
			(effects
				(font
					(size 1 1)
					(thickness 0.15)
				)
			)
		)
		(property "License" "Apache-2.0"
			(at 42.658 302.822 0)
			(layer "F.Fab")
			(hide yes)
			(effects
				(font
					(size 1 1)
					(thickness 0.15)
				)
			)
		)
		(property "MPN" "CR0402-FX-2002GLF"
			(at 42.658 302.822 0)
			(layer "F.Fab")
			(hide yes)
			(effects
				(font
					(size 1 1)
					(thickness 0.15)
				)
			)
		)
		(property "Manufacturer" "Bourns"
			(at 42.658 302.822 0)
			(layer "F.Fab")
			(hide yes)
			(effects
				(font
					(size 1 1)
					(thickness 0.15)
				)
			)
		)
		(property "Tolerance" "1%"
			(at 42.658 302.822 0)
			(layer "F.Fab")
			(hide yes)
			(effects
				(font
					(size 1 1)
					(thickness 0.15)
				)
			)
		)
		(property "Val" "20k"
			(at 42.658 302.822 0)
			(layer "F.Fab")
			(hide yes)
			(effects
				(font
					(size 1 1)
					(thickness 0.15)
				)
			)
		)
		(sheetname "Interfaces")
		(sheetfile "interfaces.kicad_sch")
		(attr smd)
		(fp_rect
			(start -0.93 -0.47)
			(end 0.93 0.47)
			(stroke
				(width 0.05)
				(type solid)
			)
			(fill no)
			(layer "F.CrtYd")
		)
		(fp_rect
			(start -0.5 -0.25)
			(end 0.5 0.25)
			(stroke
				(width 0.15)
				(type solid)
			)
			(fill no)
			(layer "F.Fab")
		)
		(pad "1" smd roundrect
			(at -0.485 0 270)
			(size 0.59 0.64)
			(layers "F.Cu" "F.Mask" "F.Paste")
			(roundrect_rratio 0.25)
			(net 459 "3V3_SYS")
			(pintype "passive")
		)
		(pad "2" smd roundrect
			(at 0.485 0 270)
			(size 0.59 0.64)
			(layers "F.Cu" "F.Mask" "F.Paste")
			(roundrect_rratio 0.25)
			(net 196 "SD_DAT3")
			(pintype "passive")
		)
	)
	(footprint "antmicro-footprints:R_0402_1005Metric"
		(layer "F.Cu")
		(at 171.597 130.082 -90)
		(descr "Resistor SMD 0402")
		(tags "resistor SMD 0402")
		(property "Reference" "R38"
			(at -0.782 -0.403 270)
			(layer "F.SilkS")
			(effects
				(font
					(size 0.7 0.7)
					(thickness 0.15)
				)
				(justify left bottom)
			)
		)
		(property "Value" "R_20k_0402"
			(at 0 1.4 270)
			(layer "F.Fab")
			(effects
				(font
					(size 0.7 0.7)
					(thickness 0.15)
				)
				(justify left bottom)
			)
		)
		(property "Description" "20k resistor in 0402 package with 1% tolerance"
			(at 0 0 270)
			(layer "F.Fab")
			(hide yes)
			(effects
				(font
					(size 1.27 1.27)
					(thickness 0.15)
				)
			)
		)
		(property "Author" "Antmicro"
			(at 41.515 301.679 0)
			(layer "F.Fab")
			(hide yes)
			(effects
				(font
					(size 1 1)
					(thickness 0.15)
				)
			)
		)
		(property "License" "Apache-2.0"
			(at 41.515 301.679 0)
			(layer "F.Fab")
			(hide yes)
			(effects
				(font
					(size 1 1)
					(thickness 0.15)
				)
			)
		)
		(property "MPN" "CR0402-FX-2002GLF"
			(at 41.515 301.679 0)
			(layer "F.Fab")
			(hide yes)
			(effects
				(font
					(size 1 1)
					(thickness 0.15)
				)
			)
		)
		(property "Manufacturer" "Bourns"
			(at 41.515 301.679 0)
			(layer "F.Fab")
			(hide yes)
			(effects
				(font
					(size 1 1)
					(thickness 0.15)
				)
			)
		)
		(property "Tolerance" "1%"
			(at 41.515 301.679 0)
			(layer "F.Fab")
			(hide yes)
			(effects
				(font
					(size 1 1)
					(thickness 0.15)
				)
			)
		)
		(property "Val" "20k"
			(at 41.515 301.679 0)
			(layer "F.Fab")
			(hide yes)
			(effects
				(font
					(size 1 1)
					(thickness 0.15)
				)
			)
		)
		(sheetname "Interfaces")
		(sheetfile "interfaces.kicad_sch")
		(attr smd)
		(fp_rect
			(start -0.93 -0.47)
			(end 0.93 0.47)
			(stroke
				(width 0.05)
				(type solid)
			)
			(fill no)
			(layer "F.CrtYd")
		)
		(fp_rect
			(start -0.5 -0.25)
			(end 0.5 0.25)
			(stroke
				(width 0.15)
				(type solid)
			)
			(fill no)
			(layer "F.Fab")
		)
		(pad "1" smd roundrect
			(at -0.485 0 270)
			(size 0.59 0.64)
			(layers "F.Cu" "F.Mask" "F.Paste")
			(roundrect_rratio 0.25)
			(net 459 "3V3_SYS")
			(pintype "passive")
		)
		(pad "2" smd roundrect
			(at 0.485 0 270)
			(size 0.59 0.64)
			(layers "F.Cu" "F.Mask" "F.Paste")
			(roundrect_rratio 0.25)
			(net 197 "SD_DAT2")
			(pintype "passive")
		)
	)
	(footprint "antmicro-footprints:SW_B3U-1000P_SMD"
		(layer "F.Cu")
		(at 213.193336 96.42168 -90)
		(property "Reference" "PROG_B1"
			(at 1.87832 -2.506664 270)
			(layer "F.SilkS")
			(effects
				(font
					(size 0.7 0.7)
					(thickness 0.15)
				)
				(justify left bottom)
			)
		)
		(property "Value" "SW_B3U-1000P"
			(at 0 2.5 270)
			(layer "F.Fab")
			(effects
				(font
					(size 0.7 0.7)
					(thickness 0.15)
				)
				(justify left bottom)
			)
		)
		(property "Description" "Tactile Switch, B3U, Top Actuated, Surface Mount, Round Button, 153 gf, 50mA at 12VDC"
			(at 0 0 270)
			(layer "F.Fab")
			(hide yes)
			(effects
				(font
					(size 1.27 1.27)
					(thickness 0.15)
				)
			)
		)
		(property "Author" "Antmicro"
			(at 116.771656 309.615016 0)
			(layer "F.Fab")
			(hide yes)
			(effects
				(font
					(size 1 1)
					(thickness 0.15)
				)
			)
		)
		(property "License" "Apache-2.0"
			(at 116.771656 309.615016 0)
			(layer "F.Fab")
			(hide yes)
			(effects
				(font
					(size 1 1)
					(thickness 0.15)
				)
			)
		)
		(property "MPN" "B3U-1000P"
			(at 116.771656 309.615016 0)
			(layer "F.Fab")
			(hide yes)
			(effects
				(font
					(size 1 1)
					(thickness 0.15)
				)
			)
		)
		(property "Manufacturer" "Omron"
			(at 116.771656 309.615016 0)
			(layer "F.Fab")
			(hide yes)
			(effects
				(font
					(size 1 1)
					(thickness 0.15)
				)
			)
		)
		(sheetname "Config SPI flash")
		(sheetfile "config-spi.kicad_sch")
		(attr smd)
		(fp_line
			(start -1.6 1.4)
			(end -1.1 1.4)
			(stroke
				(width 0.15)
				(type solid)
			)
			(layer "F.SilkS")
		)
		(fp_line
			(start -1.6 1.4)
			(end -1.6 0.95)
			(stroke
				(width 0.15)
				(type solid)
			)
			(layer "F.SilkS")
		)
		(fp_line
			(start 1.6 1.4)
			(end 1.1 1.4)
			(stroke
				(width 0.15)
				(type solid)
			)
			(layer "F.SilkS")
		)
		(fp_line
			(start 1.6 1.4)
			(end 1.6 0.95)
			(stroke
				(width 0.15)
				(type solid)
			)
			(layer "F.SilkS")
		)
		(fp_line
			(start -1.601 -0.95)
			(end -2 -0.95)
			(stroke
				(width 0.15)
				(type solid)
			)
			(layer "F.SilkS")
		)
		(fp_line
			(start -1.6 -1.4)
			(end -1.601 -0.95)
			(stroke
				(width 0.15)
				(type solid)
			)
			(layer "F.SilkS")
		)
		(fp_line
			(start -1.6 -1.4)
			(end -1.1 -1.4)
			(stroke
				(width 0.15)
				(type solid)
			)
			(layer "F.SilkS")
		)
		(fp_line
			(start 1.6 -1.4)
			(end 1.6 -0.95)
			(stroke
				(width 0.15)
				(type solid)
			)
			(layer "F.SilkS")
		)
		(fp_line
			(start 1.6 -1.4)
			(end 1.1 -1.4)
			(stroke
				(width 0.15)
				(type solid)
			)
			(layer "F.SilkS")
		)
		(fp_rect
			(start -2.249 -1.55)
			(end 2.25 1.549)
			(stroke
				(width 0.05)
				(type solid)
			)
			(fill no)
			(layer "F.CrtYd")
		)
		(fp_rect
			(start -1.5 -1.29)
			(end 1.499 1.289)
			(stroke
				(width 0.15)
				(type solid)
			)
			(fill no)
			(layer "F.Fab")
		)
		(pad "1" smd rect
			(at -1.7 0 270)
			(size 0.8 1.7)
			(layers "F.Cu" "F.Mask" "F.Paste")
			(net 208 "PROGRAM_B")
			(pinfunction "1")
			(pintype "passive")
		)
		(pad "2" smd rect
			(at 1.699 0 270)
			(size 0.8 1.7)
			(layers "F.Cu" "F.Mask" "F.Paste")
			(net 5 "GND")
			(pinfunction "2")
			(pintype "passive")
		)
	)
	(footprint "antmicro-footprints:TP_SMD_1mm"
		(layer "F.Cu")
		(at 151.4832 121.16 90)
		(property "Reference" "TP3"
			(at -2.24 -0.534 90)
			(layer "F.SilkS")
			(effects
				(font
					(size 0.7 0.7)
					(thickness 0.15)
				)
				(justify left bottom)
			)
		)
		(property "Value" "TP_1mm_SMD"
			(at 0 1.4 90)
			(layer "F.Fab")
			(effects
				(font
					(size 0.7 0.7)
					(thickness 0.15)
				)
				(justify left bottom)
			)
		)
		(property "Description" "Test Point 1mm"
			(at 0 0 90)
			(layer "F.Fab")
			(hide yes)
			(effects
				(font
					(size 1.27 1.27)
					(thickness 0.15)
				)
			)
		)
		(property "Author" "Antmicro"
			(at 272.6432 -30.3232 0)
			(layer "F.Fab")
			(hide yes)
			(effects
				(font
					(size 1 1)
					(thickness 0.15)
				)
			)
		)
		(property "License" "Apache-2.0"
			(at 272.6432 -30.3232 0)
			(layer "F.Fab")
			(hide yes)
			(effects
				(font
					(size 1 1)
					(thickness 0.15)
				)
			)
		)
		(property "MPN" ""
			(at 272.6432 -30.3232 0)
			(layer "F.Fab")
			(hide yes)
			(effects
				(font
					(size 1 1)
					(thickness 0.15)
				)
			)
		)
		(property "Manufacturer" ""
			(at 272.6432 -30.3232 0)
			(layer "F.Fab")
			(hide yes)
			(effects
				(font
					(size 1 1)
					(thickness 0.15)
				)
			)
		)
		(sheetname "Interfaces")
		(sheetfile "interfaces.kicad_sch")
		(attr exclude_from_pos_files)
		(pad "1" smd circle
			(at 0 0 90)
			(size 1 1)
			(layers "F.Cu" "F.Mask")
			(net 81 "Net-(J2-SCL)")
			(pinfunction "1")
			(pintype "passive")
		)
	)
	(footprint "antmicro-footprints:TP_SMD_1mm"
		(layer "F.Cu")
		(at 148.534 119.16 90)
		(property "Reference" "TP4"
			(at 0.36 0.0008 90)
			(layer "F.SilkS")
			(effects
				(font
					(size 0.7 0.7)
					(thickness 0.15)
				)
				(justify left bottom)
			)
		)
		(property "Value" "TP_1mm_SMD"
			(at 0 1.4 90)
			(layer "F.Fab")
			(effects
				(font
					(size 0.7 0.7)
					(thickness 0.15)
				)
				(justify left bottom)
			)
		)
		(property "Description" "Test Point 1mm"
			(at 0 0 90)
			(layer "F.Fab")
			(hide yes)
			(effects
				(font
					(size 1.27 1.27)
					(thickness 0.15)
				)
			)
		)
		(property "Author" "Antmicro"
			(at 267.694 -29.374 0)
			(layer "F.Fab")
			(hide yes)
			(effects
				(font
					(size 1 1)
					(thickness 0.15)
				)
			)
		)
		(property "License" "Apache-2.0"
			(at 267.694 -29.374 0)
			(layer "F.Fab")
			(hide yes)
			(effects
				(font
					(size 1 1)
					(thickness 0.15)
				)
			)
		)
		(property "MPN" ""
			(at 267.694 -29.374 0)
			(layer "F.Fab")
			(hide yes)
			(effects
				(font
					(size 1 1)
					(thickness 0.15)
				)
			)
		)
		(property "Manufacturer" ""
			(at 267.694 -29.374 0)
			(layer "F.Fab")
			(hide yes)
			(effects
				(font
					(size 1 1)
					(thickness 0.15)
				)
			)
		)
		(sheetname "Interfaces")
		(sheetfile "interfaces.kicad_sch")
		(attr exclude_from_pos_files)
		(pad "1" smd circle
			(at 0 0 90)
			(size 1 1)
			(layers "F.Cu" "F.Mask")
			(net 84 "Net-(J2-HPD{slash}HEAC-)")
			(pinfunction "1")
			(pintype "passive")
		)
	)
)
